(kicad_pcb
	(version 20260206)
	(generator "pcbnew")
	(generator_version "10.0")
	(general
		(thickness 1.6)
		(legacy_teardrops no)
	)
	(paper "A4")
	(title_block
		(title "04192023_DAF0TMB3IC0_F0TG_MB_C_brd_V02_OCP.brd")
		(comment 1 "Grand Teton / footprint 3579 of 8354 (J30), pads 227-291 of 291")
	)
	(layers
		(0 "F.Cu" signal "TOP")
		(4 "In1.Cu" signal "GND")
		(6 "In2.Cu" signal "IN1")
		(8 "In3.Cu" signal "GND1")
		(10 "In4.Cu" signal "IN2")
		(12 "In5.Cu" signal "GND2")
		(14 "In6.Cu" signal "IN3")
		(16 "In7.Cu" signal "GND3")
		(18 "In8.Cu" signal "VCC")
		(20 "In9.Cu" signal "VCC1")
		(22 "In10.Cu" signal "GND4")
		(24 "In11.Cu" signal "IN4")
		(26 "In12.Cu" signal "GND5")
		(28 "In13.Cu" signal "IN5")
		(30 "In14.Cu" signal "GND6")
		(32 "In15.Cu" signal "IN6")
		(34 "In16.Cu" signal "GND7")
		(2 "B.Cu" signal "BOTTOM")
		(9 "F.Adhes" user "F.Adhesive")
		(11 "B.Adhes" user "B.Adhesive")
		(13 "F.Paste" user "Package Geometry/Pastemask Top")
		(15 "B.Paste" user "Package Geometry/Pastemask Bottom")
		(5 "F.SilkS" user "Ref Des/Silkscreen Top")
		(7 "B.SilkS" user "Ref Des/Silkscreen Bottom")
		(1 "F.Mask" user "Board Geometry/Soldermask Top")
		(3 "B.Mask" user "Board Geometry/Soldermask Bottom")
		(17 "Dwgs.User" user "User.Drawings")
		(19 "Cmts.User" user "User.Comments")
		(21 "Eco1.User" user "User.Eco1")
		(23 "Eco2.User" user "User.Eco2")
		(25 "Edge.Cuts" user "Board Geometry/Outline")
		(27 "Margin" user)
		(31 "F.CrtYd" user "Package Geometry/Place Bound Top")
		(29 "B.CrtYd" user "Package Geometry/Place Bound Bottom")
		(35 "F.Fab" user "Ref Des/Assembly Top")
		(33 "B.Fab" user "Ref Des/Assembly Bottom")
	)
	(footprint ""
		(layer "F.Cu")
		(at 34.74593 -255.560322 180)
		(property "Reference" "J30"
			(at 3.12293 -81.850992 0)
			(unlocked yes)
			(layer "F.SilkS")
			(effects
				(font
					(size 0.7874 0.5842)
					(thickness 0.1524)
				)
			)
		)
		(property "Value" ""
			(at 0 0 180)
			(layer "F.Fab")
			(effects
				(font
					(size 1.27 1.27)
				)
			)
		)
		(duplicate_pad_numbers_are_jumpers no)
		(pad "227" smd rect
			(at 2.050034 11.474958 90)
			(size 0.519938 1.4986)
			(layers "F.Cu" "F.Mask" "F.Paste")
			(net "M_D_CPU1_SB_PAR")
		)
		(pad "228" smd rect
			(at 2.050034 12.325096 90)
			(size 0.519938 1.4986)
			(layers "F.Cu" "F.Mask" "F.Paste")
			(net "GND")
		)
		(pad "229" smd rect
			(at 2.050034 13.17498 90)
			(size 0.519938 1.4986)
			(layers "F.Cu" "F.Mask" "F.Paste")
			(net "M_D_CPU1_SB_CS_N<1>")
		)
		(pad "230" smd rect
			(at 2.050034 14.025118 90)
			(size 0.519938 1.4986)
			(layers "F.Cu" "F.Mask" "F.Paste")
			(net "GND")
		)
		(pad "231" smd rect
			(at 2.050034 14.875002 90)
			(size 0.519938 1.4986)
			(layers "F.Cu" "F.Mask" "F.Paste")
			(net "Net_2303")
		)
		(pad "232" smd rect
			(at 2.050034 15.724886 90)
			(size 0.519938 1.4986)
			(layers "F.Cu" "F.Mask" "F.Paste")
			(net "Net_2304")
		)
		(pad "233" smd rect
			(at 2.050034 16.575024 90)
			(size 0.519938 1.4986)
			(layers "F.Cu" "F.Mask" "F.Paste")
			(net "GND")
		)
		(pad "234" smd rect
			(at 2.050034 17.424908 90)
			(size 0.519938 1.4986)
			(layers "F.Cu" "F.Mask" "F.Paste")
			(net "M_D_CPU1_SB_CB<6>")
		)
		(pad "235" smd rect
			(at 2.050034 18.275046 90)
			(size 0.519938 1.4986)
			(layers "F.Cu" "F.Mask" "F.Paste")
			(net "GND")
		)
		(pad "236" smd rect
			(at 2.050034 19.12493 90)
			(size 0.519938 1.4986)
			(layers "F.Cu" "F.Mask" "F.Paste")
			(net "M_D_CPU1_SB_CB<7>")
		)
		(pad "237" smd rect
			(at 2.050034 19.975068 90)
			(size 0.519938 1.4986)
			(layers "F.Cu" "F.Mask" "F.Paste")
			(net "GND")
		)
		(pad "238" smd rect
			(at 2.050034 20.824952 90)
			(size 0.519938 1.4986)
			(layers "F.Cu" "F.Mask" "F.Paste")
			(net "M_D_CPU1_SB_DQS_DN<4>")
		)
		(pad "239" smd rect
			(at 2.050034 21.67509 90)
			(size 0.519938 1.4986)
			(layers "F.Cu" "F.Mask" "F.Paste")
			(net "M_D_CPU1_SB_DQS_DP<4>")
		)
		(pad "240" smd rect
			(at 2.050034 22.524974 90)
			(size 0.519938 1.4986)
			(layers "F.Cu" "F.Mask" "F.Paste")
			(net "GND")
		)
		(pad "241" smd rect
			(at 2.050034 23.375112 90)
			(size 0.519938 1.4986)
			(layers "F.Cu" "F.Mask" "F.Paste")
			(net "M_D_CPU1_SB_CB<2>")
		)
		(pad "242" smd rect
			(at 2.050034 24.224996 90)
			(size 0.519938 1.4986)
			(layers "F.Cu" "F.Mask" "F.Paste")
			(net "GND")
		)
		(pad "243" smd rect
			(at 2.050034 25.07488 90)
			(size 0.519938 1.4986)
			(layers "F.Cu" "F.Mask" "F.Paste")
			(net "M_D_CPU1_SB_CB<3>")
		)
		(pad "244" smd rect
			(at 2.050034 25.925018 90)
			(size 0.519938 1.4986)
			(layers "F.Cu" "F.Mask" "F.Paste")
			(net "GND")
		)
		(pad "245" smd rect
			(at 2.050034 26.774902 90)
			(size 0.519938 1.4986)
			(layers "F.Cu" "F.Mask" "F.Paste")
			(net "M_D_CPU1_SB_DQ<2>")
		)
		(pad "246" smd rect
			(at 2.050034 27.62504 90)
			(size 0.519938 1.4986)
			(layers "F.Cu" "F.Mask" "F.Paste")
			(net "GND")
		)
		(pad "247" smd rect
			(at 2.050034 28.474924 90)
			(size 0.519938 1.4986)
			(layers "F.Cu" "F.Mask" "F.Paste")
			(net "M_D_CPU1_SB_DQ<3>")
		)
		(pad "248" smd rect
			(at 2.050034 29.325062 90)
			(size 0.519938 1.4986)
			(layers "F.Cu" "F.Mask" "F.Paste")
			(net "GND")
		)
		(pad "249" smd rect
			(at 2.050034 30.174946 90)
			(size 0.519938 1.4986)
			(layers "F.Cu" "F.Mask" "F.Paste")
			(net "M_D_CPU1_SB_DQS_DN<5>")
		)
		(pad "250" smd rect
			(at 2.050034 31.025084 90)
			(size 0.519938 1.4986)
			(layers "F.Cu" "F.Mask" "F.Paste")
			(net "M_D_CPU1_SB_DQS_DP<5>")
		)
		(pad "251" smd rect
			(at 2.050034 31.874968 90)
			(size 0.519938 1.4986)
			(layers "F.Cu" "F.Mask" "F.Paste")
			(net "GND")
		)
		(pad "252" smd rect
			(at 2.050034 32.725106 90)
			(size 0.519938 1.4986)
			(layers "F.Cu" "F.Mask" "F.Paste")
			(net "M_D_CPU1_SB_DQ<6>")
		)
		(pad "253" smd rect
			(at 2.050034 33.57499 90)
			(size 0.519938 1.4986)
			(layers "F.Cu" "F.Mask" "F.Paste")
			(net "GND")
		)
		(pad "254" smd rect
			(at 2.050034 34.425128 90)
			(size 0.519938 1.4986)
			(layers "F.Cu" "F.Mask" "F.Paste")
			(net "M_D_CPU1_SB_DQ<7>")
		)
		(pad "255" smd rect
			(at 2.050034 35.275012 90)
			(size 0.519938 1.4986)
			(layers "F.Cu" "F.Mask" "F.Paste")
			(net "GND")
		)
		(pad "256" smd rect
			(at 2.050034 36.124896 90)
			(size 0.519938 1.4986)
			(layers "F.Cu" "F.Mask" "F.Paste")
			(net "M_D_CPU1_SB_DQ<10>")
		)
		(pad "257" smd rect
			(at 2.050034 36.975034 90)
			(size 0.519938 1.4986)
			(layers "F.Cu" "F.Mask" "F.Paste")
			(net "GND")
		)
		(pad "258" smd rect
			(at 2.050034 37.824918 90)
			(size 0.519938 1.4986)
			(layers "F.Cu" "F.Mask" "F.Paste")
			(net "M_D_CPU1_SB_DQ<11>")
		)
		(pad "259" smd rect
			(at 2.050034 38.675056 90)
			(size 0.519938 1.4986)
			(layers "F.Cu" "F.Mask" "F.Paste")
			(net "GND")
		)
		(pad "260" smd rect
			(at 2.050034 39.52494 90)
			(size 0.519938 1.4986)
			(layers "F.Cu" "F.Mask" "F.Paste")
			(net "M_D_CPU1_SB_DQS_DN<6>")
		)
		(pad "261" smd rect
			(at 2.050034 40.375078 90)
			(size 0.519938 1.4986)
			(layers "F.Cu" "F.Mask" "F.Paste")
			(net "M_D_CPU1_SB_DQS_DP<6>")
		)
		(pad "262" smd rect
			(at 2.050034 41.224962 90)
			(size 0.519938 1.4986)
			(layers "F.Cu" "F.Mask" "F.Paste")
			(net "GND")
		)
		(pad "263" smd rect
			(at 2.050034 42.0751 90)
			(size 0.519938 1.4986)
			(layers "F.Cu" "F.Mask" "F.Paste")
			(net "M_D_CPU1_SB_DQ<14>")
		)
		(pad "264" smd rect
			(at 2.050034 42.924984 90)
			(size 0.519938 1.4986)
			(layers "F.Cu" "F.Mask" "F.Paste")
			(net "GND")
		)
		(pad "265" smd rect
			(at 2.050034 43.775122 90)
			(size 0.519938 1.4986)
			(layers "F.Cu" "F.Mask" "F.Paste")
			(net "M_D_CPU1_SB_DQ<15>")
		)
		(pad "266" smd rect
			(at 2.050034 44.625006 90)
			(size 0.519938 1.4986)
			(layers "F.Cu" "F.Mask" "F.Paste")
			(net "GND")
		)
		(pad "267" smd rect
			(at 2.050034 45.47489 90)
			(size 0.519938 1.4986)
			(layers "F.Cu" "F.Mask" "F.Paste")
			(net "M_D_CPU1_SB_DQ<18>")
		)
		(pad "268" smd rect
			(at 2.050034 46.325028 90)
			(size 0.519938 1.4986)
			(layers "F.Cu" "F.Mask" "F.Paste")
			(net "GND")
		)
		(pad "269" smd rect
			(at 2.050034 47.174912 90)
			(size 0.519938 1.4986)
			(layers "F.Cu" "F.Mask" "F.Paste")
			(net "M_D_CPU1_SB_DQ<19>")
		)
		(pad "270" smd rect
			(at 2.050034 48.02505 90)
			(size 0.519938 1.4986)
			(layers "F.Cu" "F.Mask" "F.Paste")
			(net "GND")
		)
		(pad "271" smd rect
			(at 2.050034 48.874934 90)
			(size 0.519938 1.4986)
			(layers "F.Cu" "F.Mask" "F.Paste")
			(net "M_D_CPU1_SB_DQS_DN<7>")
		)
		(pad "272" smd rect
			(at 2.050034 49.725072 90)
			(size 0.519938 1.4986)
			(layers "F.Cu" "F.Mask" "F.Paste")
			(net "M_D_CPU1_SB_DQS_DP<7>")
		)
		(pad "273" smd rect
			(at 2.050034 50.574956 90)
			(size 0.519938 1.4986)
			(layers "F.Cu" "F.Mask" "F.Paste")
			(net "GND")
		)
		(pad "274" smd rect
			(at 2.050034 51.425094 90)
			(size 0.519938 1.4986)
			(layers "F.Cu" "F.Mask" "F.Paste")
			(net "M_D_CPU1_SB_DQ<22>")
		)
		(pad "275" smd rect
			(at 2.050034 52.274978 90)
			(size 0.519938 1.4986)
			(layers "F.Cu" "F.Mask" "F.Paste")
			(net "GND")
		)
		(pad "276" smd rect
			(at 2.050034 53.125116 90)
			(size 0.519938 1.4986)
			(layers "F.Cu" "F.Mask" "F.Paste")
			(net "M_D_CPU1_SB_DQ<23>")
		)
		(pad "277" smd rect
			(at 2.050034 53.975 90)
			(size 0.519938 1.4986)
			(layers "F.Cu" "F.Mask" "F.Paste")
			(net "GND")
		)
		(pad "278" smd rect
			(at 2.050034 54.824884 90)
			(size 0.519938 1.4986)
			(layers "F.Cu" "F.Mask" "F.Paste")
			(net "M_D_CPU1_SB_DQ<26>")
		)
		(pad "279" smd rect
			(at 2.050034 55.675022 90)
			(size 0.519938 1.4986)
			(layers "F.Cu" "F.Mask" "F.Paste")
			(net "GND")
		)
		(pad "280" smd rect
			(at 2.050034 56.524906 90)
			(size 0.519938 1.4986)
			(layers "F.Cu" "F.Mask" "F.Paste")
			(net "M_D_CPU1_SB_DQ<27>")
		)
		(pad "281" smd rect
			(at 2.050034 57.375044 90)
			(size 0.519938 1.4986)
			(layers "F.Cu" "F.Mask" "F.Paste")
			(net "GND")
		)
		(pad "282" smd rect
			(at 2.050034 58.224928 90)
			(size 0.519938 1.4986)
			(layers "F.Cu" "F.Mask" "F.Paste")
			(net "M_D_CPU1_SB_DQS_DN<8>")
		)
		(pad "283" smd rect
			(at 2.050034 59.075066 90)
			(size 0.519938 1.4986)
			(layers "F.Cu" "F.Mask" "F.Paste")
			(net "M_D_CPU1_SB_DQS_DP<8>")
		)
		(pad "284" smd rect
			(at 2.050034 59.92495 90)
			(size 0.519938 1.4986)
			(layers "F.Cu" "F.Mask" "F.Paste")
			(net "GND")
		)
		(pad "285" smd rect
			(at 2.050034 60.775088 90)
			(size 0.519938 1.4986)
			(layers "F.Cu" "F.Mask" "F.Paste")
			(net "M_D_CPU1_SB_DQ<30>")
		)
		(pad "286" smd rect
			(at 2.050034 61.624972 90)
			(size 0.519938 1.4986)
			(layers "F.Cu" "F.Mask" "F.Paste")
			(net "GND")
		)
		(pad "287" smd rect
			(at 2.050034 62.47511 90)
			(size 0.519938 1.4986)
			(layers "F.Cu" "F.Mask" "F.Paste")
			(net "M_D_CPU1_SB_DQ<31>")
		)
		(pad "288" smd rect
			(at 2.050034 63.324994 90)
			(size 0.519938 1.4986)
			(layers "F.Cu" "F.Mask" "F.Paste")
			(net "GND")
		)
		(pad "G1" thru_hole oval
			(at 0 -68.97497 90)
			(size 1.7272 3.4798)
			(drill oval 1.2192 2.4638)
			(layers "*.Cu" "*.Mask")
			(remove_unused_layers no)
			(net "GND")
			(clearance 0.127)
			(thermal_gap 0.127)
		)
		(pad "G2" thru_hole oval
			(at 0 3.875024 90)
			(size 1.7272 3.4798)
			(drill oval 1.2192 2.4638)
			(layers "*.Cu" "*.Mask")
			(remove_unused_layers no)
			(net "GND")
			(clearance 0.127)
			(thermal_gap 0.127)
		)
		(pad "G3" thru_hole oval
			(at 0 68.97497 90)
			(size 1.7272 3.4798)
			(drill oval 1.2192 2.4638)
			(layers "*.Cu" "*.Mask")
			(remove_unused_layers no)
			(net "GND")
			(clearance 0.127)
			(thermal_gap 0.127)
		)
	)
)
